(kicad_pcb
	(version 20241229)
	(generator "pcbnew")
	(generator_version "9.0")
	(general
		(thickness 1.6)
		(legacy_teardrops no)
	)
	(paper "A4")
	(title_block
		(title "GMSL Deserializer")
		(date "2025-10-09")
		(rev "1.0.4")
		(company "Antmicro Ltd")
		(comment 1 "www.antmicro.com")
		(comment 9 "footprints 15-20 of 235")
	)
	(layers
		(0 "F.Cu" signal)
		(4 "In1.Cu" power)
		(6 "In2.Cu" power)
		(2 "B.Cu" signal)
		(9 "F.Adhes" user "F.Adhesive")
		(11 "B.Adhes" user "B.Adhesive")
		(13 "F.Paste" user)
		(15 "B.Paste" user)
		(5 "F.SilkS" user "F.Silkscreen")
		(7 "B.SilkS" user "B.Silkscreen")
		(1 "F.Mask" user)
		(3 "B.Mask" user)
		(17 "Dwgs.User" user "User.Drawings")
		(19 "Cmts.User" user "User.Comments")
		(21 "Eco1.User" user "User.Eco1")
		(23 "Eco2.User" user "User.Eco2")
		(25 "Edge.Cuts" user)
		(27 "Margin" user)
		(31 "F.CrtYd" user "F.Courtyard")
		(29 "B.CrtYd" user "B.Courtyard")
		(35 "F.Fab" user)
		(33 "B.Fab" user)
	)
	(footprint "antmicro-footprints:TP_SMD_0.75mm"
		(layer "F.Cu")
		(at 155.448 97.89)
		(property "Reference" "TP7"
			(at 0 -0.6 0)
			(layer "F.SilkS")
			(hide yes)
			(effects
				(font
					(size 0.7 0.7)
					(thickness 0.15)
				)
				(justify left bottom)
			)
		)
		(property "Value" "TP_0.75mm_SMD"
			(at 0 1.2 0)
			(layer "F.Fab")
			(effects
				(font
					(size 0.7 0.7)
					(thickness 0.15)
				)
				(justify left bottom)
			)
		)
		(property "Description" "SMT test point"
			(at 0 0 0)
			(layer "F.Fab")
			(hide yes)
			(effects
				(font
					(size 1.27 1.27)
					(thickness 0.15)
				)
			)
		)
		(property "Author" "Antmicro"
			(at 0 0 0)
			(layer "F.Fab")
			(hide yes)
			(effects
				(font
					(size 1 1)
					(thickness 0.15)
				)
			)
		)
		(property "License" "Apache-2.0"
			(at 0 0 0)
			(layer "F.Fab")
			(hide yes)
			(effects
				(font
					(size 1 1)
					(thickness 0.15)
				)
			)
		)
		(property "MPN" ""
			(at 0 0 0)
			(layer "F.Fab")
			(hide yes)
			(effects
				(font
					(size 1 1)
					(thickness 0.15)
				)
			)
		)
		(property "Manufacturer" ""
			(at 0 0 0)
			(layer "F.Fab")
			(hide yes)
			(effects
				(font
					(size 1 1)
					(thickness 0.15)
				)
			)
		)
		(sheetname "/Connectors/")
		(sheetfile "connectors.kicad_sch")
		(fp_circle
			(center 0 0)
			(end 0.475 0)
			(stroke
				(width 0.05)
				(type default)
			)
			(fill no)
			(layer "F.CrtYd")
		)
		(pad "1" smd circle
			(at 0 0)
			(size 0.75 0.75)
			(layers "F.Cu" "F.Mask")
			(net 113 "/Connectors/FFC_5V")
			(pinfunction "1")
			(pintype "passive")
		)
	)
	(footprint "antmicro-footprints:SOD-123FL"
		(layer "F.Cu")
		(at 175.005 51.308)
		(property "Reference" "D1"
			(at 2.063307 -0.360854 0)
			(layer "F.SilkS")
			(effects
				(font
					(size 0.7 0.7)
					(thickness 0.15)
				)
				(justify left bottom)
			)
		)
		(property "Value" "SMF4L15A"
			(at 0 1.967 0)
			(layer "F.Fab")
			(effects
				(font
					(size 0.7 0.7)
					(thickness 0.15)
				)
				(justify left bottom)
			)
		)
		(property "Datasheet" "https://www.littelfuse.com/media?resourcetype=datasheets&itemid=d2ba8fab-1de3-4176-8530-f36ecb0b8799&filename=smf4l"
			(at 0 0 0)
			(layer "F.Fab")
			(hide yes)
			(effects
				(font
					(size 1.27 1.27)
					(thickness 0.15)
				)
			)
		)
		(property "Description" "Unidirectional TVS, 30 kV,  SOD-123FL, 15 V, 600 pF"
			(at 0 0 0)
			(layer "F.Fab")
			(hide yes)
			(effects
				(font
					(size 1.27 1.27)
					(thickness 0.15)
				)
			)
		)
		(property "Author" "Antmicro"
			(at 0 0 0)
			(layer "F.Fab")
			(hide yes)
			(effects
				(font
					(size 1 1)
					(thickness 0.15)
				)
			)
		)
		(property "License" "Apache-2.0"
			(at 0 0 0)
			(layer "F.Fab")
			(hide yes)
			(effects
				(font
					(size 1 1)
					(thickness 0.15)
				)
			)
		)
		(property "MPN" "SMF4L15A"
			(at 0 0 0)
			(layer "F.Fab")
			(hide yes)
			(effects
				(font
					(size 1 1)
					(thickness 0.15)
				)
			)
		)
		(property "Manufacturer" "Littelfuse"
			(at 0 0 0)
			(layer "F.Fab")
			(hide yes)
			(effects
				(font
					(size 1 1)
					(thickness 0.15)
				)
			)
		)
		(sheetname "/Connectors/")
		(sheetfile "connectors.kicad_sch")
		(attr smd)
		(fp_line
			(start -2.3 -1.1)
			(end -2.3 1.1)
			(stroke
				(width 0.15)
				(type solid)
			)
			(layer "F.SilkS")
		)
		(fp_line
			(start -2.3 1.1)
			(end 0 1.1)
			(stroke
				(width 0.15)
				(type solid)
			)
			(layer "F.SilkS")
		)
		(fp_line
			(start 0 -1.1)
			(end -2.3 -1.1)
			(stroke
				(width 0.15)
				(type solid)
			)
			(layer "F.SilkS")
		)
		(fp_rect
			(start -2.35 -1.125)
			(end 2.35 1.125)
			(stroke
				(width 0.05)
				(type solid)
			)
			(fill no)
			(layer "F.CrtYd")
		)
		(fp_rect
			(start -1.825 -0.875)
			(end 1.824 0.873)
			(stroke
				(width 0.15)
				(type solid)
			)
			(fill no)
			(layer "F.Fab")
		)
		(fp_rect
			(start -0.775 -0.875)
			(end -0.525 0.875)
			(stroke
				(width 0.15)
				(type solid)
			)
			(fill yes)
			(layer "F.Fab")
		)
		(pad "1" smd roundrect
			(at -1.43 0)
			(size 1.34 1.8)
			(layers "F.Cu" "F.Mask" "F.Paste")
			(roundrect_rratio 0.14)
			(net 2 "/Connectors/DC_UNFUSED")
			(pinfunction "C")
			(pintype "passive")
		)
		(pad "2" smd roundrect
			(at 1.429 0)
			(size 1.34 1.8)
			(layers "F.Cu" "F.Mask" "F.Paste")
			(roundrect_rratio 0.14)
			(net 1 "GND")
			(pinfunction "A")
			(pintype "passive")
		)
	)
	(footprint "antmicro-footprints:C_0402_1005Metric"
		(layer "F.Cu")
		(at 151.13 74.676 45)
		(descr "Capacitor SMD 0402")
		(tags "capacitor SMD 0402")
		(property "Reference" "C29"
			(at 4.003639 0.193747 45)
			(layer "F.SilkS")
			(effects
				(font
					(size 0.7 0.7)
					(thickness 0.15)
				)
				(justify left bottom)
			)
		)
		(property "Value" "C_100n_0402"
			(at -1.022927 2.155213 45)
			(layer "F.Fab")
			(effects
				(font
					(size 0.7 0.7)
					(thickness 0.15)
				)
				(justify left bottom)
			)
		)
		(property "Datasheet" "https://www.murata.com/products/productdetail?partno=GRM155R61H104KE14%23"
			(at 0 0 45)
			(layer "F.Fab")
			(hide yes)
			(effects
				(font
					(size 1.27 1.27)
					(thickness 0.15)
				)
			)
		)
		(property "Description" "SMD Multilayer Ceramic Capacitor, 0.1 µF, 50 V, 0402 [1005 Metric], ± 10%, X5R, GRM Series"
			(at 0 0 45)
			(layer "F.Fab")
			(hide yes)
			(effects
				(font
					(size 1.27 1.27)
					(thickness 0.15)
				)
			)
		)
		(property "Author" "Antmicro"
			(at 97.068858 -84.992954 0)
			(layer "F.Fab")
			(hide yes)
			(effects
				(font
					(size 1 1)
					(thickness 0.15)
				)
			)
		)
		(property "Dielectric" "X5R"
			(at 97.068858 -84.992954 0)
			(layer "F.Fab")
			(hide yes)
			(effects
				(font
					(size 1 1)
					(thickness 0.15)
				)
			)
		)
		(property "License" "Apache-2.0"
			(at 97.068858 -84.992954 0)
			(layer "F.Fab")
			(hide yes)
			(effects
				(font
					(size 1 1)
					(thickness 0.15)
				)
			)
		)
		(property "MPN" "GRM155R61H104KE14D"
			(at 97.068858 -84.992954 0)
			(layer "F.Fab")
			(hide yes)
			(effects
				(font
					(size 1 1)
					(thickness 0.15)
				)
			)
		)
		(property "Manufacturer" "Murata"
			(at 97.068858 -84.992954 0)
			(layer "F.Fab")
			(hide yes)
			(effects
				(font
					(size 1 1)
					(thickness 0.15)
				)
			)
		)
		(property "Val" "100n"
			(at 97.068858 -84.992954 0)
			(layer "F.Fab")
			(hide yes)
			(effects
				(font
					(size 1 1)
					(thickness 0.15)
				)
			)
		)
		(property "Voltage" "50V"
			(at 97.068858 -84.992954 0)
			(layer "F.Fab")
			(hide yes)
			(effects
				(font
					(size 1 1)
					(thickness 0.15)
				)
			)
		)
		(sheetname "/Deserializer/")
		(sheetfile "deserializer.kicad_sch")
		(attr smd)
		(fp_poly
			(pts
				(xy -0.925 -0.47) (xy 0.925 -0.47) (xy 0.925 0.47) (xy -0.925 0.47)
			)
			(stroke
				(width 0.05)
				(type default)
			)
			(fill no)
			(layer "F.CrtYd")
		)
		(fp_line
			(start -0.494 -0.25)
			(end 0.504 -0.25)
			(stroke
				(width 0.15)
				(type solid)
			)
			(layer "F.Fab")
		)
		(fp_line
			(start -0.494 0.248)
			(end -0.494 -0.25)
			(stroke
				(width 0.15)
				(type solid)
			)
			(layer "F.Fab")
		)
		(fp_line
			(start 0.504 -0.25)
			(end 0.504 0.248)
			(stroke
				(width 0.15)
				(type solid)
			)
			(layer "F.Fab")
		)
		(fp_line
			(start 0.504 0.248)
			(end -0.494 0.248)
			(stroke
				(width 0.15)
				(type solid)
			)
			(layer "F.Fab")
		)
		(pad "1" smd roundrect
			(at -0.48 0 45)
			(size 0.59 0.64)
			(layers "F.Cu" "F.Mask" "F.Paste")
			(roundrect_rratio 0.25)
			(net 15 "/Deserializer/SIOC_P")
			(pintype "passive")
		)
		(pad "2" smd roundrect
			(at 0.48 0 45)
			(size 0.59 0.64)
			(layers "F.Cu" "F.Mask" "F.Paste")
			(roundrect_rratio 0.25)
			(net 116 "/Connectors/PoCC")
			(pintype "passive")
		)
	)
	(footprint "antmicro-footprints:R_0402_1005Metric"
		(layer "F.Cu")
		(at 173.656 64.87 90)
		(descr "Resistor SMD 0402")
		(tags "resistor SMD 0402")
		(property "Reference" "R58"
			(at -2.996432 0.322713 90)
			(layer "F.SilkS")
			(effects
				(font
					(size 0.7 0.7)
					(thickness 0.15)
				)
				(justify left bottom)
			)
		)
		(property "Value" "R_2k2_0402"
			(at -1.011843 1.772047 90)
			(layer "F.Fab")
			(effects
				(font
					(size 0.7 0.7)
					(thickness 0.15)
				)
				(justify left bottom)
			)
		)
		(property "Datasheet" "https://www.bourns.com/docs/product-datasheets/cr.pdf"
			(at 0 0 90)
			(layer "F.Fab")
			(hide yes)
			(effects
				(font
					(size 1.27 1.27)
					(thickness 0.15)
				)
			)
		)
		(property "Description" "SMD Chip Resistor, 2.2 kohm, ± 1%, 62.5 mW, 0402 [1005 Metric], Thick Film, General Purpose"
			(at 0 0 90)
			(layer "F.Fab")
			(hide yes)
			(effects
				(font
					(size 1.27 1.27)
					(thickness 0.15)
				)
			)
		)
		(property "Author" "Antmicro"
			(at 238.526 -108.786 0)
			(layer "F.Fab")
			(hide yes)
			(effects
				(font
					(size 1 1)
					(thickness 0.15)
				)
			)
		)
		(property "License" "Apache-2.0"
			(at 238.526 -108.786 0)
			(layer "F.Fab")
			(hide yes)
			(effects
				(font
					(size 1 1)
					(thickness 0.15)
				)
			)
		)
		(property "MPN" "CR0402-FX-2201GLF"
			(at 238.526 -108.786 0)
			(layer "F.Fab")
			(hide yes)
			(effects
				(font
					(size 1 1)
					(thickness 0.15)
				)
			)
		)
		(property "Manufacturer" "Bourns"
			(at 238.526 -108.786 0)
			(layer "F.Fab")
			(hide yes)
			(effects
				(font
					(size 1 1)
					(thickness 0.15)
				)
			)
		)
		(property "Tolerance" "1%"
			(at 238.526 -108.786 0)
			(layer "F.Fab")
			(hide yes)
			(effects
				(font
					(size 1 1)
					(thickness 0.15)
				)
			)
		)
		(property "Val" "2k2"
			(at 238.526 -108.786 0)
			(layer "F.Fab")
			(hide yes)
			(effects
				(font
					(size 1 1)
					(thickness 0.15)
				)
			)
		)
		(sheetname "/Connectors/")
		(sheetfile "connectors.kicad_sch")
		(attr smd)
		(fp_rect
			(start -0.925 -0.47)
			(end 0.925 0.47)
			(stroke
				(width 0.05)
				(type default)
			)
			(fill no)
			(layer "F.CrtYd")
		)
		(fp_rect
			(start -0.5 -0.25)
			(end 0.5 0.25)
			(stroke
				(width 0.15)
				(type solid)
			)
			(fill no)
			(layer "F.Fab")
		)
		(pad "1" smd roundrect
			(at -0.48 0 90)
			(size 0.59 0.64)
			(layers "F.Cu" "F.Mask" "F.Paste")
			(roundrect_rratio 0.25)
			(net 133 "Net-(U8-A_{1})")
			(pintype "passive")
		)
		(pad "2" smd roundrect
			(at 0.48 0 90)
			(size 0.59 0.64)
			(layers "F.Cu" "F.Mask" "F.Paste")
			(roundrect_rratio 0.25)
			(net 3 "+1V8")
			(pintype "passive")
		)
	)
	(footprint "antmicro-footprints:R_0402_1005Metric"
		(layer "F.Cu")
		(at 162.052 56.642 90)
		(descr "Resistor SMD 0402")
		(tags "resistor SMD 0402")
		(property "Reference" "R27"
			(at -1.122484 1.262 90)
			(layer "F.SilkS")
			(effects
				(font
					(size 0.7 0.7)
					(thickness 0.15)
				)
				(justify left bottom)
			)
		)
		(property "Value" "R_5k1_0402"
			(at -1.011843 1.772047 90)
			(layer "F.Fab")
			(effects
				(font
					(size 0.7 0.7)
					(thickness 0.15)
				)
				(justify left bottom)
			)
		)
		(property "Datasheet" "https://www.bourns.com/docs/product-datasheets/cr.pdf"
			(at 0 0 90)
			(layer "F.Fab")
			(hide yes)
			(effects
				(font
					(size 1.27 1.27)
					(thickness 0.15)
				)
			)
		)
		(property "Description" "SMD Chip Resistor, 5.1 kohm, ± 1%, 63 mW, 0402 [1005 Metric], Thick Film, General Purpose"
			(at 0 0 90)
			(layer "F.Fab")
			(hide yes)
			(effects
				(font
					(size 1.27 1.27)
					(thickness 0.15)
				)
			)
		)
		(property "Author" "Antmicro"
			(at 218.694 -105.41 0)
			(layer "F.Fab")
			(hide yes)
			(effects
				(font
					(size 1 1)
					(thickness 0.15)
				)
			)
		)
		(property "License" "Apache-2.0"
			(at 218.694 -105.41 0)
			(layer "F.Fab")
			(hide yes)
			(effects
				(font
					(size 1 1)
					(thickness 0.15)
				)
			)
		)
		(property "MPN" "CR0402-FX-5101GLF"
			(at 218.694 -105.41 0)
			(layer "F.Fab")
			(hide yes)
			(effects
				(font
					(size 1 1)
					(thickness 0.15)
				)
			)
		)
		(property "Manufacturer" "Bourns"
			(at 218.694 -105.41 0)
			(layer "F.Fab")
			(hide yes)
			(effects
				(font
					(size 1 1)
					(thickness 0.15)
				)
			)
		)
		(property "Tolerance" "1%"
			(at 218.694 -105.41 0)
			(layer "F.Fab")
			(hide yes)
			(effects
				(font
					(size 1 1)
					(thickness 0.15)
				)
			)
		)
		(property "Val" "5k1"
			(at 218.694 -105.41 0)
			(layer "F.Fab")
			(hide yes)
			(effects
				(font
					(size 1 1)
					(thickness 0.15)
				)
			)
		)
		(sheetname "/Power/")
		(sheetfile "power.kicad_sch")
		(attr smd)
		(fp_rect
			(start -0.925 -0.47)
			(end 0.925 0.47)
			(stroke
				(width 0.05)
				(type default)
			)
			(fill no)
			(layer "F.CrtYd")
		)
		(fp_rect
			(start -0.5 -0.25)
			(end 0.5 0.25)
			(stroke
				(width 0.15)
				(type solid)
			)
			(fill no)
			(layer "F.Fab")
		)
		(pad "1" smd roundrect
			(at -0.48 0 90)
			(size 0.59 0.64)
			(layers "F.Cu" "F.Mask" "F.Paste")
			(roundrect_rratio 0.25)
			(net 54 "Net-(L4-Pad2)")
			(pintype "passive")
		)
		(pad "2" smd roundrect
			(at 0.48 0 90)
			(size 0.59 0.64)
			(layers "F.Cu" "F.Mask" "F.Paste")
			(roundrect_rratio 0.25)
			(net 58 "Net-(L12-Pad1)")
			(pintype "passive")
		)
	)
	(footprint "antmicro-footprints:C_0402_1005Metric"
		(layer "F.Cu")
		(at 135.564 66.5564 90)
		(descr "Capacitor SMD 0402")
		(tags "capacitor SMD 0402")
		(property "Reference" "C11"
			(at -1.7696 1.215 90)
			(layer "F.SilkS")
			(effects
				(font
					(size 0.7 0.7)
					(thickness 0.15)
				)
				(justify left bottom)
			)
		)
		(property "Value" "C_10n_0402"
			(at -1.022927 2.155213 90)
			(layer "F.Fab")
			(effects
				(font
					(size 0.7 0.7)
					(thickness 0.15)
				)
				(justify left bottom)
			)
		)
		(property "Datasheet" "https://www.murata.com/products/productdetail?partno=GRM155R71H103KA88%23"
			(at 0 0 90)
			(layer "F.Fab")
			(hide yes)
			(effects
				(font
					(size 1.27 1.27)
					(thickness 0.15)
				)
			)
		)
		(property "Description" "SMD Multilayer Ceramic Capacitor, 10000 pF, 50 V, 0402 [1005 Metric], ± 10%, X7R, GRM Series"
			(at 0 0 90)
			(layer "F.Fab")
			(hide yes)
			(effects
				(font
					(size 1.27 1.27)
					(thickness 0.15)
				)
			)
		)
		(property "Author" "Antmicro"
			(at 202.1204 -69.0076 0)
			(layer "F.Fab")
			(hide yes)
			(effects
				(font
					(size 1 1)
					(thickness 0.15)
				)
			)
		)
		(property "Dielectric" "X7R"
			(at 202.1204 -69.0076 0)
			(layer "F.Fab")
			(hide yes)
			(effects
				(font
					(size 1 1)
					(thickness 0.15)
				)
			)
		)
		(property "License" "Apache-2.0"
			(at 202.1204 -69.0076 0)
			(layer "F.Fab")
			(hide yes)
			(effects
				(font
					(size 1 1)
					(thickness 0.15)
				)
			)
		)
		(property "MPN" "GRM155R71H103KA88D"
			(at 202.1204 -69.0076 0)
			(layer "F.Fab")
			(hide yes)
			(effects
				(font
					(size 1 1)
					(thickness 0.15)
				)
			)
		)
		(property "Manufacturer" "Murata"
			(at 202.1204 -69.0076 0)
			(layer "F.Fab")
			(hide yes)
			(effects
				(font
					(size 1 1)
					(thickness 0.15)
				)
			)
		)
		(property "Val" "10n"
			(at 202.1204 -69.0076 0)
			(layer "F.Fab")
			(hide yes)
			(effects
				(font
					(size 1 1)
					(thickness 0.15)
				)
			)
		)
		(property "Voltage" "50V"
			(at 202.1204 -69.0076 0)
			(layer "F.Fab")
			(hide yes)
			(effects
				(font
					(size 1 1)
					(thickness 0.15)
				)
			)
		)
		(sheetname "/Power/")
		(sheetfile "power.kicad_sch")
		(attr smd)
		(fp_rect
			(start -0.925 -0.47)
			(end 0.925 0.47)
			(stroke
				(width 0.05)
				(type default)
			)
			(fill no)
			(layer "F.CrtYd")
		)
		(fp_line
			(start 0.504 -0.25)
			(end 0.504 0.248)
			(stroke
				(width 0.15)
				(type solid)
			)
			(layer "F.Fab")
		)
		(fp_line
			(start -0.494 -0.25)
			(end 0.504 -0.25)
			(stroke
				(width 0.15)
				(type solid)
			)
			(layer "F.Fab")
		)
		(fp_line
			(start 0.504 0.248)
			(end -0.494 0.248)
			(stroke
				(width 0.15)
				(type solid)
			)
			(layer "F.Fab")
		)
		(fp_line
			(start -0.494 0.248)
			(end -0.494 -0.25)
			(stroke
				(width 0.15)
				(type solid)
			)
			(layer "F.Fab")
		)
		(pad "1" smd roundrect
			(at -0.48 0 90)
			(size 0.59 0.64)
			(layers "F.Cu" "F.Mask" "F.Paste")
			(roundrect_rratio 0.25)
			(net 1 "GND")
			(pintype "passive")
		)
		(pad "2" smd roundrect
			(at 0.48 0 90)
			(size 0.59 0.64)
			(layers "F.Cu" "F.Mask" "F.Paste")
			(roundrect_rratio 0.25)
			(net 4 "+12V")
			(pintype "passive")
		)
	)
)
